# BASEBOARD_FAB2 (Tioga Pass) — schematic netlist excerpt (pin names and nets, part order shuffled) for the footprints in the layout excerpt that follows; sources: Cadence DE-HDL packaged netlist, KiCad conversion of Wiwynn_Tioga_Pass_MB.brd

R25W145  RES  0.0 5% CHIP  pkg 0402  page 145 : A = RST_SYSTEM_BTN_R_N ; B = RST_SYSTEM_BTN_N
C2U25  CAP_A  0.1UF 16V 10% X7R  pkg 0402V  page 108 : A = P3V3 ; B = GND
R25W132  RES  4.75K 1% CHIP  pkg 0402  page 252 : A = P5V_VGA_D ; B = I2C_BMC_VGA_DDC_SCL_G

(kicad_pcb
	(version 20260206)
	(generator "pcbnew")
	(generator_version "10.0")
	(general
		(thickness 1.6)
		(legacy_teardrops no)
	)
	(paper "A4")
	(title_block
		(title "Wiwynn_Tioga_Pass_MB.brd")
		(comment 1 "Tioga Pass / footprints 2676-2678 of 4770")
	)
	(layers
		(0 "F.Cu" signal "TOP")
		(4 "In1.Cu" signal "L2GND")
		(6 "In2.Cu" signal "L3")
		(8 "In3.Cu" signal "L4GND")
		(10 "In4.Cu" signal "L5")
		(12 "In5.Cu" signal "L6GND")
		(14 "In6.Cu" signal "L7VCC")
		(16 "In7.Cu" signal "L8VCC")
		(18 "In8.Cu" signal "L9GND")
		(20 "In9.Cu" signal "L10")
		(22 "In10.Cu" signal "L11GND")
		(24 "In11.Cu" signal "L12")
		(26 "In12.Cu" signal "L13GND")
		(2 "B.Cu" signal "BOTTOM")
		(9 "F.Adhes" user "F.Adhesive")
		(11 "B.Adhes" user "B.Adhesive")
		(13 "F.Paste" user "Package Geometry/Pastemask Top")
		(15 "B.Paste" user "Package Geometry/Pastemask Bottom")
		(5 "F.SilkS" user "Ref Des/Silkscreen Top")
		(7 "B.SilkS" user "Ref Des/Silkscreen Bottom")
		(1 "F.Mask" user "Board Geometry/Soldermask Top")
		(3 "B.Mask" user "Board Geometry/Soldermask Bottom")
		(17 "Dwgs.User" user "User.Drawings")
		(19 "Cmts.User" user "User.Comments")
		(21 "Eco1.User" user "User.Eco1")
		(23 "Eco2.User" user "User.Eco2")
		(25 "Edge.Cuts" user "Board Geometry/Outline")
		(27 "Margin" user)
		(31 "F.CrtYd" user "Package Geometry/Place Bound Top")
		(29 "B.CrtYd" user "Package Geometry/Place Bound Bottom")
		(35 "F.Fab" user "Ref Des/Assembly Top")
		(33 "B.Fab" user "Ref Des/Assembly Bottom")
	)
	(footprint ""
		(layer "B.Cu")
		(at 496.529614 -47.605696 -90)
		(property "Reference" "R25W132"
			(at 0.8382 -0.67818 270)
			(unlocked yes)
			(layer "B.SilkS")
			(effects
				(font
					(size 0.4064 0.254)
					(thickness 0.1524)
				)
				(justify left mirror)
			)
		)
		(property "Value" ""
			(at 0 0 90)
			(layer "B.Fab")
			(effects
				(font
					(size 1.27 1.27)
				)
				(justify mirror)
			)
		)
		(duplicate_pad_numbers_are_jumpers no)
		(fp_poly
			(pts
				(xy 0.2794 -0.1016) (xy -0.2794 -0.1016) (xy -0.2794 0.9906) (xy 0.2794 0.9906)
			)
			(stroke
				(width 0)
				(type default)
			)
			(fill no)
			(layer "B.CrtYd")
		)
		(fp_line
			(start -0.2794 0.9906)
			(end -0.2794 -0.1016)
			(stroke
				(width 0.1)
				(type default)
			)
			(layer "B.Fab")
		)
		(fp_line
			(start 0.2794 0.9906)
			(end -0.2794 0.9906)
			(stroke
				(width 0.1)
				(type default)
			)
			(layer "B.Fab")
		)
		(fp_line
			(start -0.2794 -0.1016)
			(end 0.2794 -0.1016)
			(stroke
				(width 0.1)
				(type default)
			)
			(layer "B.Fab")
		)
		(fp_line
			(start 0.2794 -0.1016)
			(end 0.2794 0.9906)
			(stroke
				(width 0.1)
				(type default)
			)
			(layer "B.Fab")
		)
		(pad "1" smd rect
			(at 0 0 90)
			(size 0.508 0.508)
			(layers "B.Cu" "B.Mask" "B.Paste")
			(net "P5V_VGA_D")
		)
		(pad "2" smd rect
			(at 0 0.889 90)
			(size 0.508 0.508)
			(layers "B.Cu" "B.Mask" "B.Paste")
			(net "I2C_BMC_VGA_DDC_SCL_G")
		)
		(zone
			(layer "B.Cu")
			(hatch none 0.5)
			(connect_pads
				(clearance 0)
			)
			(min_thickness 0.25)
			(keepout
				(tracks not_allowed)
				(vias allowed)
				(pads allowed)
				(copperpour not_allowed)
				(footprints allowed)
			)
			(placement
				(enabled no)
				(sheetname "")
			)
			(fill
				(thermal_gap 0.5)
				(thermal_bridge_width 0.5)
				(island_removal_mode 0)
			)
			(polygon
				(pts
					(xy 495.894614 -47.351696) (xy 495.894614 -47.859696) (xy 496.275614 -47.859696) (xy 496.275614 -47.351696)
				)
			)
		)
		(zone
			(layer "B.Cu")
			(hatch none 0.5)
			(connect_pads
				(clearance 0)
			)
			(min_thickness 0.25)
			(keepout
				(tracks allowed)
				(vias not_allowed)
				(pads allowed)
				(copperpour not_allowed)
				(footprints allowed)
			)
			(placement
				(enabled no)
				(sheetname "")
			)
			(fill
				(thermal_gap 0.5)
				(thermal_bridge_width 0.5)
				(island_removal_mode 0)
			)
			(polygon
				(pts
					(xy 496.275614 -47.351696) (xy 496.275614 -47.859696) (xy 495.894614 -47.859696) (xy 495.894614 -47.351696)
				)
			)
		)
	)
	(footprint ""
		(layer "B.Cu")
		(at 467.791038 -6.858 90)
		(property "Reference" "C2U25"
			(at 0 0 90)
			(layer "B.SilkS")
			(hide yes)
			(effects
				(font
					(size 1.27 1.27)
				)
				(justify mirror)
			)
		)
		(property "Value" ""
			(at 0 0 90)
			(layer "B.Fab")
			(effects
				(font
					(size 1.27 1.27)
				)
				(justify mirror)
			)
		)
		(duplicate_pad_numbers_are_jumpers no)
		(fp_poly
			(pts
				(xy -0.3048 -0.1016) (xy -0.3048 0.9906) (xy 0.3048 0.9906) (xy 0.3048 -0.1016)
			)
			(stroke
				(width 0)
				(type default)
			)
			(fill no)
			(layer "B.CrtYd")
		)
		(fp_line
			(start 0.3048 -0.1016)
			(end 0.3048 0.9906)
			(stroke
				(width 0.1)
				(type default)
			)
			(layer "B.Fab")
		)
		(fp_line
			(start -0.3048 -0.1016)
			(end 0.3048 -0.1016)
			(stroke
				(width 0.1)
				(type default)
			)
			(layer "B.Fab")
		)
		(fp_line
			(start 0.3048 0.9906)
			(end -0.3048 0.9906)
			(stroke
				(width 0.1)
				(type default)
			)
			(layer "B.Fab")
		)
		(fp_line
			(start -0.3048 0.9906)
			(end -0.3048 -0.1016)
			(stroke
				(width 0.1)
				(type default)
			)
			(layer "B.Fab")
		)
		(pad "1" smd rect
			(at 0 0 270)
			(size 0.508 0.508)
			(layers "B.Cu" "B.Mask" "B.Paste")
			(net "P3V3")
		)
		(pad "2" smd rect
			(at 0 0.889 270)
			(size 0.508 0.508)
			(layers "B.Cu" "B.Mask" "B.Paste")
			(net "GND")
		)
		(zone
			(layer "B.Cu")
			(hatch none 0.5)
			(connect_pads
				(clearance 0)
			)
			(min_thickness 0.25)
			(keepout
				(tracks allowed)
				(vias not_allowed)
				(pads allowed)
				(copperpour not_allowed)
				(footprints allowed)
			)
			(placement
				(enabled no)
				(sheetname "")
			)
			(fill
				(thermal_gap 0.5)
				(thermal_bridge_width 0.5)
				(island_removal_mode 0)
			)
			(polygon
				(pts
					(xy 468.045038 -7.112) (xy 468.045038 -6.604) (xy 468.426038 -6.604) (xy 468.426038 -7.112)
				)
			)
		)
		(zone
			(layer "B.Cu")
			(hatch none 0.5)
			(connect_pads
				(clearance 0)
			)
			(min_thickness 0.25)
			(keepout
				(tracks not_allowed)
				(vias allowed)
				(pads allowed)
				(copperpour not_allowed)
				(footprints allowed)
			)
			(placement
				(enabled no)
				(sheetname "")
			)
			(fill
				(thermal_gap 0.5)
				(thermal_bridge_width 0.5)
				(island_removal_mode 0)
			)
			(polygon
				(pts
					(xy 468.426038 -7.112) (xy 468.426038 -6.604) (xy 468.045038 -6.604) (xy 468.045038 -7.112)
				)
			)
		)
	)
	(footprint ""
		(layer "B.Cu")
		(at 454.4822 -42.545 180)
		(property "Reference" "R25W145"
			(at 0.8382 -0.67818 180)
			(unlocked yes)
			(layer "B.SilkS")
			(effects
				(font
					(size 0.4064 0.254)
					(thickness 0.1524)
				)
				(justify left mirror)
			)
		)
		(property "Value" ""
			(at 0 0 0)
			(layer "B.Fab")
			(effects
				(font
					(size 1.27 1.27)
				)
				(justify mirror)
			)
		)
		(duplicate_pad_numbers_are_jumpers no)
		(fp_poly
			(pts
				(xy 0.2794 -0.1016) (xy -0.2794 -0.1016) (xy -0.2794 0.9906) (xy 0.2794 0.9906)
			)
			(stroke
				(width 0)
				(type default)
			)
			(fill no)
			(layer "B.CrtYd")
		)
		(fp_line
			(start 0.2794 0.9906)
			(end -0.2794 0.9906)
			(stroke
				(width 0.1)
				(type default)
			)
			(layer "B.Fab")
		)
		(fp_line
			(start 0.2794 -0.1016)
			(end 0.2794 0.9906)
			(stroke
				(width 0.1)
				(type default)
			)
			(layer "B.Fab")
		)
		(fp_line
			(start -0.2794 0.9906)
			(end -0.2794 -0.1016)
			(stroke
				(width 0.1)
				(type default)
			)
			(layer "B.Fab")
		)
		(fp_line
			(start -0.2794 -0.1016)
			(end 0.2794 -0.1016)
			(stroke
				(width 0.1)
				(type default)
			)
			(layer "B.Fab")
		)
		(pad "1" smd rect
			(at 0 0)
			(size 0.508 0.508)
			(layers "B.Cu" "B.Mask" "B.Paste")
			(net "RST_SYSTEM_BTN_R_N")
		)
		(pad "2" smd rect
			(at 0 0.889)
			(size 0.508 0.508)
			(layers "B.Cu" "B.Mask" "B.Paste")
			(net "RST_SYSTEM_BTN_N")
		)
		(zone
			(layer "B.Cu")
			(hatch none 0.5)
			(connect_pads
				(clearance 0)
			)
			(min_thickness 0.25)
			(keepout
				(tracks not_allowed)
				(vias allowed)
				(pads allowed)
				(copperpour not_allowed)
				(footprints allowed)
			)
			(placement
				(enabled no)
				(sheetname "")
			)
			(fill
				(thermal_gap 0.5)
				(thermal_bridge_width 0.5)
				(island_removal_mode 0)
			)
			(polygon
				(pts
					(xy 454.2282 -43.18) (xy 454.7362 -43.18) (xy 454.7362 -42.799) (xy 454.2282 -42.799)
				)
			)
		)
		(zone
			(layer "B.Cu")
			(hatch none 0.5)
			(connect_pads
				(clearance 0)
			)
			(min_thickness 0.25)
			(keepout
				(tracks allowed)
				(vias not_allowed)
				(pads allowed)
				(copperpour not_allowed)
				(footprints allowed)
			)
			(placement
				(enabled no)
				(sheetname "")
			)
			(fill
				(thermal_gap 0.5)
				(thermal_bridge_width 0.5)
				(island_removal_mode 0)
			)
			(polygon
				(pts
					(xy 454.2282 -42.799) (xy 454.7362 -42.799) (xy 454.7362 -43.18) (xy 454.2282 -43.18)
				)
			)
		)
	)
)
